(kicad_pcb
	(version 20260206)
	(generator "pcbnew")
	(generator_version "10.0")
	(general
		(thickness 1.6)
		(legacy_teardrops no)
	)
	(paper "A4")
	(title_block
		(title "ptb — 12523-1.1018WZS1506.brd")
		(comment 1 "Open Vault / Knox (Wiwynn) / footprints 55-60 of 61")
	)
	(layers
		(0 "F.Cu" signal "TOP")
		(4 "In1.Cu" signal "L2GND")
		(6 "In2.Cu" signal "L3VCC")
		(2 "B.Cu" signal "BOTTOM")
		(9 "F.Adhes" user "F.Adhesive")
		(11 "B.Adhes" user "B.Adhesive")
		(13 "F.Paste" user "Package Geometry/Pastemask Top")
		(15 "B.Paste" user "Package Geometry/Pastemask Bottom")
		(5 "F.SilkS" user "Ref Des/Silkscreen Top")
		(7 "B.SilkS" user "Ref Des/Silkscreen Bottom")
		(1 "F.Mask" user "Board Geometry/Soldermask Top")
		(3 "B.Mask" user "Board Geometry/Soldermask Bottom")
		(17 "Dwgs.User" user "User.Drawings")
		(19 "Cmts.User" user "User.Comments")
		(21 "Eco1.User" user "User.Eco1")
		(23 "Eco2.User" user "User.Eco2")
		(25 "Edge.Cuts" user "Board Geometry/Outline")
		(27 "Margin" user)
		(31 "F.CrtYd" user "Package Geometry/Place Bound Top")
		(29 "B.CrtYd" user "Package Geometry/Place Bound Bottom")
		(35 "F.Fab" user "Ref Des/Assembly Top")
		(33 "B.Fab" user "Ref Des/Assembly Bottom")
	)
	(footprint ""
		(layer "F.Cu")
		(at 9.372092 -84.692744 90)
		(property "Reference" "R384"
			(at 0 0 90)
			(layer "F.SilkS")
			(hide yes)
			(effects
				(font
					(size 1.27 1.27)
				)
			)
		)
		(property "Value" "0R2J-2-GP"
			(at 0.064008 -3.993896 90)
			(unlocked yes)
			(layer "F.Fab")
			(hide yes)
			(effects
				(font
					(size 1.016 1.016)
					(thickness 0.1524)
				)
			)
		)
		(property "Device Type" "R402H16"
			(at 0.064008 -5.517896 90)
			(unlocked yes)
			(layer "F.Fab")
			(hide yes)
			(effects
				(font
					(size 1.016 1.016)
					(thickness 0.1524)
				)
			)
		)
		(duplicate_pad_numbers_are_jumpers no)
		(fp_line
			(start 0.508 -0.9398)
			(end -0.508 -0.9398)
			(stroke
				(width 0.1524)
				(type default)
			)
			(layer "F.SilkS")
		)
		(fp_line
			(start -0.508 -0.9398)
			(end -0.508 0.9398)
			(stroke
				(width 0.1524)
				(type default)
			)
			(layer "F.SilkS")
		)
		(fp_rect
			(start -0.508 0.9398)
			(end 0.508 -0.9398)
			(stroke
				(width 0)
				(type default)
			)
			(fill no)
			(layer "F.CrtYd")
		)
		(fp_rect
			(start -0.508 0.9398)
			(end 0.508 -0.9398)
			(stroke
				(width 0)
				(type default)
			)
			(fill no)
			(layer "F.Fab")
		)
		(pad "1" smd custom
			(at 0 -0.4445 90)
			(size 0.1397 0.1397)
			(layers "F.Cu" "F.Mask" "F.Paste")
			(net "PWM_EXP_A")
			(options
				(clearance outline)
				(anchor circle)
			)
			(primitives
				(gr_poly
					(pts
						(arc
							(start -0.1778 -0.2794)
							(mid -0.249642 -0.249642)
							(end -0.2794 -0.1778)
						)
						(arc
							(start -0.2794 0.1778)
							(mid -0.249642 0.249642)
							(end -0.1778 0.2794)
						)
						(arc
							(start 0.1778 0.2794)
							(mid 0.249642 0.249642)
							(end 0.2794 0.1778)
						)
						(arc
							(start 0.2794 -0.1778)
							(mid 0.249642 -0.249642)
							(end 0.1778 -0.2794)
						)
					)
					(width 0)
					(fill yes)
				)
			)
		)
		(pad "2" smd custom
			(at 0 0.4445 90)
			(size 0.1397 0.1397)
			(layers "F.Cu" "F.Mask" "F.Paste")
			(net "PWM_EXP_A_OUT")
			(options
				(clearance outline)
				(anchor circle)
			)
			(primitives
				(gr_poly
					(pts
						(arc
							(start -0.1778 -0.2794)
							(mid -0.249642 -0.249642)
							(end -0.2794 -0.1778)
						)
						(arc
							(start -0.2794 0.1778)
							(mid -0.249642 0.249642)
							(end -0.1778 0.2794)
						)
						(arc
							(start 0.1778 0.2794)
							(mid 0.249642 0.249642)
							(end 0.2794 0.1778)
						)
						(arc
							(start 0.2794 -0.1778)
							(mid 0.249642 -0.249642)
							(end 0.1778 -0.2794)
						)
					)
					(width 0)
					(fill yes)
				)
			)
		)
	)
	(footprint ""
		(layer "F.Cu")
		(at 13.650468 -94.361508)
		(property "Reference" "U51"
			(at 0 0 0)
			(layer "F.SilkS")
			(hide yes)
			(effects
				(font
					(size 1.27 1.27)
				)
			)
		)
		(property "Value" "PCA9511ADP-T-GP"
			(at 0 -13.1572 0)
			(unlocked yes)
			(layer "F.Fab")
			(hide yes)
			(effects
				(font
					(size 1.016 1.016)
					(thickness 0.1524)
				)
			)
		)
		(property "Device Type" "SSOIC8-2H44"
			(at 0 -15.1892 0)
			(unlocked yes)
			(layer "F.Fab")
			(hide yes)
			(effects
				(font
					(size 1.016 1.016)
					(thickness 0.1524)
				)
			)
		)
		(duplicate_pad_numbers_are_jumpers no)
		(fp_line
			(start -1.9304 -1.016)
			(end 1.0922 -1.016)
			(stroke
				(width 0.1524)
				(type default)
			)
			(layer "F.SilkS")
		)
		(fp_line
			(start -1.9304 1.016)
			(end -1.9304 -1.016)
			(stroke
				(width 0.1524)
				(type default)
			)
			(layer "F.SilkS")
		)
		(fp_line
			(start -1.7018 1.0414)
			(end -1.7018 2.9718)
			(stroke
				(width 0.635)
				(type default)
			)
			(layer "F.SilkS")
		)
		(fp_line
			(start -1.524 0)
			(end -1.9304 -0.4064)
			(stroke
				(width 0.1524)
				(type default)
			)
			(layer "F.SilkS")
		)
		(fp_line
			(start -1.524 0)
			(end -1.9304 0.4064)
			(stroke
				(width 0.1524)
				(type default)
			)
			(layer "F.SilkS")
		)
		(fp_line
			(start 1.0922 -1.016)
			(end 1.0922 1.016)
			(stroke
				(width 0.1524)
				(type default)
			)
			(layer "F.SilkS")
		)
		(fp_line
			(start 1.0922 1.016)
			(end -1.9304 1.016)
			(stroke
				(width 0.1524)
				(type default)
			)
			(layer "F.SilkS")
		)
		(fp_poly
			(pts
				(xy -1.1938 -1.016) (xy 1.0922 -1.016) (xy 1.0922 1.016) (xy -1.1938 1.016)
			)
			(stroke
				(width 0)
				(type default)
			)
			(fill yes)
			(layer "F.SilkS")
		)
		(fp_rect
			(start -2.0066 3.3401)
			(end 2.0066 -3.3401)
			(stroke
				(width 0)
				(type default)
			)
			(fill no)
			(layer "F.CrtYd")
		)
		(fp_poly
			(pts
				(xy -2.0066 -3.3401) (xy 2.0066 -3.3401) (xy 2.0066 3.3401) (xy -2.0066 3.3401)
			)
			(stroke
				(width 0)
				(type default)
			)
			(fill no)
			(layer "F.Fab")
		)
		(pad "1" smd rect
			(at -0.97536 2.0701)
			(size 0.4064 1.524)
			(layers "F.Cu" "F.Mask" "F.Paste")
			(net "I2C_C_BUF_EN")
		)
		(pad "2" smd rect
			(at -0.32512 2.0701)
			(size 0.4064 1.524)
			(layers "F.Cu" "F.Mask" "F.Paste")
			(net "I2C_C_BUF_SCLOUT")
		)
		(pad "3" smd rect
			(at 0.32512 2.0701)
			(size 0.4064 1.524)
			(layers "F.Cu" "F.Mask" "F.Paste")
			(net "I2C_C_BUF_SCLIN")
		)
		(pad "4" smd rect
			(at 0.97536 2.0701)
			(size 0.4064 1.524)
			(layers "F.Cu" "F.Mask" "F.Paste")
			(net "GND")
		)
		(pad "5" smd rect
			(at 0.97536 -2.0701)
			(size 0.4064 1.524)
			(layers "F.Cu" "F.Mask" "F.Paste")
			(net "I2C_C_BUF_READY")
		)
		(pad "6" smd rect
			(at 0.32512 -2.0701)
			(size 0.4064 1.524)
			(layers "F.Cu" "F.Mask" "F.Paste")
			(net "I2C_C_BUF_SDAIN")
		)
		(pad "7" smd rect
			(at -0.32512 -2.0701)
			(size 0.4064 1.524)
			(layers "F.Cu" "F.Mask" "F.Paste")
			(net "I2C_C_BUF_SDAOUT")
		)
		(pad "8" smd rect
			(at -0.97536 -2.0701)
			(size 0.4064 1.524)
			(layers "F.Cu" "F.Mask" "F.Paste")
			(net "P3V3")
		)
	)
	(footprint ""
		(layer "F.Cu")
		(at 133.223 -82.804 90)
		(property "Reference" "R376"
			(at 0 0 90)
			(layer "F.SilkS")
			(hide yes)
			(effects
				(font
					(size 1.27 1.27)
				)
			)
		)
		(property "Value" "100KR2F-L1-GP"
			(at 0.064008 -3.993896 90)
			(unlocked yes)
			(layer "F.Fab")
			(hide yes)
			(effects
				(font
					(size 1.016 1.016)
					(thickness 0.1524)
				)
			)
		)
		(property "Device Type" "R402H16"
			(at 0.064008 -5.517896 90)
			(unlocked yes)
			(layer "F.Fab")
			(hide yes)
			(effects
				(font
					(size 1.016 1.016)
					(thickness 0.1524)
				)
			)
		)
		(duplicate_pad_numbers_are_jumpers no)
		(fp_line
			(start 0.508 -0.9398)
			(end -0.508 -0.9398)
			(stroke
				(width 0.1524)
				(type default)
			)
			(layer "F.SilkS")
		)
		(fp_line
			(start -0.508 -0.9398)
			(end -0.508 0.9398)
			(stroke
				(width 0.1524)
				(type default)
			)
			(layer "F.SilkS")
		)
		(fp_rect
			(start -0.508 0.9398)
			(end 0.508 -0.9398)
			(stroke
				(width 0)
				(type default)
			)
			(fill no)
			(layer "F.CrtYd")
		)
		(fp_rect
			(start -0.508 0.9398)
			(end 0.508 -0.9398)
			(stroke
				(width 0)
				(type default)
			)
			(fill no)
			(layer "F.Fab")
		)
		(pad "1" smd custom
			(at 0 -0.4445 90)
			(size 0.1397 0.1397)
			(layers "F.Cu" "F.Mask" "F.Paste")
			(net "P3V3")
			(options
				(clearance outline)
				(anchor circle)
			)
			(primitives
				(gr_poly
					(pts
						(arc
							(start -0.1778 -0.2794)
							(mid -0.249642 -0.249642)
							(end -0.2794 -0.1778)
						)
						(arc
							(start -0.2794 0.1778)
							(mid -0.249642 0.249642)
							(end -0.1778 0.2794)
						)
						(arc
							(start 0.1778 0.2794)
							(mid 0.249642 0.249642)
							(end 0.2794 0.1778)
						)
						(arc
							(start 0.2794 -0.1778)
							(mid 0.249642 -0.249642)
							(end 0.1778 -0.2794)
						)
					)
					(width 0)
					(fill yes)
				)
			)
		)
		(pad "2" smd custom
			(at 0 0.4445 90)
			(size 0.1397 0.1397)
			(layers "F.Cu" "F.Mask" "F.Paste")
			(net "TRAY PRESENT_OUT#_C")
			(options
				(clearance outline)
				(anchor circle)
			)
			(primitives
				(gr_poly
					(pts
						(arc
							(start -0.1778 -0.2794)
							(mid -0.249642 -0.249642)
							(end -0.2794 -0.1778)
						)
						(arc
							(start -0.2794 0.1778)
							(mid -0.249642 0.249642)
							(end -0.1778 0.2794)
						)
						(arc
							(start 0.1778 0.2794)
							(mid 0.249642 0.249642)
							(end 0.2794 0.1778)
						)
						(arc
							(start 0.2794 -0.1778)
							(mid 0.249642 -0.249642)
							(end 0.1778 -0.2794)
						)
					)
					(width 0)
					(fill yes)
				)
			)
		)
	)
	(footprint ""
		(layer "F.Cu")
		(at 7.659878 -105.499916)
		(property "Reference" "H2"
			(at 0 0 0)
			(layer "F.SilkS")
			(hide yes)
			(effects
				(font
					(size 1.27 1.27)
				)
			)
		)
		(property "Value" "HTE9B9R355-R-766"
			(at -8.9789 -1.1176 0)
			(unlocked yes)
			(layer "F.Fab")
			(hide yes)
			(effects
				(font
					(size 1.016 1.016)
					(thickness 0.1524)
				)
			)
		)
		(property "Device Type" "HTE9B9R355-R-766"
			(at -8.9789 -2.6416 0)
			(unlocked yes)
			(layer "F.Fab")
			(hide yes)
			(effects
				(font
					(size 1.016 1.016)
					(thickness 0.1524)
				)
			)
		)
		(duplicate_pad_numbers_are_jumpers no)
		(fp_poly
			(pts
				(arc
					(start -4.8133 0)
					(mid 4.8133 0)
					(end -4.8133 0)
				)
			)
			(stroke
				(width 0)
				(type default)
			)
			(fill no)
			(layer "B.CrtYd")
		)
		(fp_poly
			(pts
				(arc
					(start 0 -4.8133)
					(mid 4.8133 0)
					(end 0 4.8133)
				)
				(xy -7.9629 4.8133) (xy -7.9629 -4.8133)
			)
			(stroke
				(width 0)
				(type default)
			)
			(fill no)
			(layer "F.CrtYd")
		)
		(fp_poly
			(pts
				(arc
					(start -4.8133 0)
					(mid 4.8133 0)
					(end -4.8133 0)
				)
			)
			(stroke
				(width 0)
				(type default)
			)
			(fill no)
			(layer "B.Fab")
		)
		(fp_poly
			(pts
				(arc
					(start 0 -4.8133)
					(mid 4.8133 0)
					(end 0 4.8133)
				)
				(xy -7.9629 4.8133) (xy -7.9629 -4.8133)
			)
			(stroke
				(width 0)
				(type default)
			)
			(fill no)
			(layer "F.Fab")
		)
		(pad "1" thru_hole custom
			(at 0 0)
			(size 2.25425 2.25425)
			(drill 3.556)
			(layers "*.Cu" "*.Mask")
			(remove_unused_layers no)
			(net "GND")
			(clearance -3.7973)
			(thermal_gap 0.3048)
			(options
				(clearance outline)
				(anchor circle)
			)
			(primitives
				(gr_poly
					(pts
						(arc
							(start 1.5748 -4.5085)
							(mid 6.0833 0)
							(end 1.5748 4.5085)
						)
						(xy -6.0833 4.5085) (xy -6.0833 -4.5085)
					)
					(width 0)
					(fill yes)
				)
			)
			(padstack
				(mode front_inner_back)
				(layer "Inner"
					(shape circle)
					(size 3.9624 3.9624)
					(clearance 0.3048)
				)
				(layer "B.Cu"
					(shape circle)
					(size 9.017 9.017)
					(clearance -2.2225)
				)
			)
		)
	)
	(footprint ""
		(layer "F.Cu")
		(at 155.66009 -87.700104 90)
		(property "Reference" "LED16"
			(at 0 0 90)
			(layer "F.SilkS")
			(hide yes)
			(effects
				(font
					(size 1.27 1.27)
				)
			)
		)
		(property "Value" "LED-IR-1-GP"
			(at -3.513074 -0.460502 90)
			(unlocked yes)
			(layer "F.Fab")
			(hide yes)
			(effects
				(font
					(size 1.016 1.016)
					(thickness 0.1524)
				)
			)
		)
		(property "Device Type" "LED3640AKH166"
			(at -3.513074 -1.984502 90)
			(unlocked yes)
			(layer "F.Fab")
			(hide yes)
			(effects
				(font
					(size 1.016 1.016)
					(thickness 0.1524)
				)
			)
		)
		(duplicate_pad_numbers_are_jumpers no)
		(fp_line
			(start 2.0574 -2.6543)
			(end -2.1844 -2.6543)
			(stroke
				(width 0.1524)
				(type default)
			)
			(layer "F.SilkS")
		)
		(fp_line
			(start -2.1844 -2.6543)
			(end -2.1844 2.6543)
			(stroke
				(width 0.1524)
				(type default)
			)
			(layer "F.SilkS")
		)
		(fp_line
			(start 2.0574 2.6543)
			(end 2.0574 -2.6543)
			(stroke
				(width 0.1524)
				(type default)
			)
			(layer "F.SilkS")
		)
		(fp_line
			(start -2.1844 2.6543)
			(end 2.0574 2.6543)
			(stroke
				(width 0.1524)
				(type default)
			)
			(layer "F.SilkS")
		)
		(fp_line
			(start -2.1844 2.8321)
			(end 2.0574 2.8321)
			(stroke
				(width 0.508)
				(type default)
			)
			(layer "F.SilkS")
		)
		(fp_rect
			(start -1.8034 1.9939)
			(end 1.8034 -1.9939)
			(stroke
				(width 0)
				(type default)
			)
			(fill no)
			(layer "F.CrtYd")
		)
		(fp_poly
			(pts
				(xy -2.4384 2.7305) (xy -2.4384 -2.7305) (xy 2.3114 -2.7305) (xy 2.3114 1.98882) (xy 1.8034 1.98882)
				(xy 1.8034 -1.9939) (xy -1.8034 -1.9939) (xy -1.8034 1.9939) (xy 2.3114 1.9939) (xy 2.3114 2.7305)
			)
			(stroke
				(width 0)
				(type default)
			)
			(fill no)
			(layer "F.CrtYd")
		)
		(fp_rect
			(start -2.4384 2.7305)
			(end 2.3114 -2.7305)
			(stroke
				(width 0)
				(type default)
			)
			(fill no)
			(layer "F.Fab")
		)
		(pad "A" smd rect
			(at -0.374904 -1.455674 90)
			(size 3.0988 1.8796)
			(layers "F.Cu" "F.Mask" "F.Paste")
			(net "P3V3")
		)
		(pad "K" smd rect
			(at -0.374904 1.455674 90)
			(size 3.0988 1.8796)
			(layers "F.Cu" "F.Mask" "F.Paste")
			(net "EMITTER_K")
		)
	)
	(footprint ""
		(layer "F.Cu")
		(at 136.68629 -47.187358 180)
		(property "Reference" "TC4"
			(at 0 0 180)
			(layer "F.SilkS")
			(hide yes)
			(effects
				(font
					(size 1.27 1.27)
				)
			)
		)
		(property "Value" "ST68U16VDM-1-GP"
			(at 0 -9.6012 180)
			(unlocked yes)
			(layer "F.Fab")
			(hide yes)
			(effects
				(font
					(size 1.016 1.016)
					(thickness 0.1524)
				)
			)
		)
		(property "Device Type" "CT7343H79"
			(at 0 -11.1252 180)
			(unlocked yes)
			(layer "F.Fab")
			(hide yes)
			(effects
				(font
					(size 1.016 1.016)
					(thickness 0.1524)
				)
			)
		)
		(duplicate_pad_numbers_are_jumpers no)
		(fp_line
			(start 2.286 4.8768)
			(end -2.286 4.8768)
			(stroke
				(width 0.1524)
				(type default)
			)
			(layer "F.SilkS")
		)
		(fp_line
			(start 2.286 2.032)
			(end 2.286 4.8768)
			(stroke
				(width 0.1524)
				(type default)
			)
			(layer "F.SilkS")
		)
		(fp_line
			(start 2.286 -2.032)
			(end 2.286 -4.8768)
			(stroke
				(width 0.1524)
				(type default)
			)
			(layer "F.SilkS")
		)
		(fp_line
			(start 2.286 -4.8768)
			(end -2.286 -4.8768)
			(stroke
				(width 0.1524)
				(type default)
			)
			(layer "F.SilkS")
		)
		(fp_line
			(start 2.1082 -4.699)
			(end -2.1082 -4.699)
			(stroke
				(width 0.508)
				(type default)
			)
			(layer "F.SilkS")
		)
		(fp_line
			(start -2.286 4.8768)
			(end -2.286 2.032)
			(stroke
				(width 0.1524)
				(type default)
			)
			(layer "F.SilkS")
		)
		(fp_line
			(start -2.286 -4.8768)
			(end -2.286 -2.032)
			(stroke
				(width 0.1524)
				(type default)
			)
			(layer "F.SilkS")
		)
		(fp_rect
			(start -2.1463 3.6449)
			(end 2.1463 -3.6449)
			(stroke
				(width 0)
				(type default)
			)
			(fill no)
			(layer "F.CrtYd")
		)
		(fp_poly
			(pts
				(xy -2.54 4.953) (xy -2.54 4.2926) (xy -3.81 4.2926) (xy -3.81 -4.2926) (xy -2.54 -4.2926) (xy -2.54 -4.953)
				(xy 2.54 -4.953) (xy 2.54 -4.2926) (xy 3.81 -4.2926) (xy 3.81 -1.6256) (xy 2.1463 -1.6256) (xy 2.1463 -3.6449)
				(xy -2.1463 -3.6449) (xy -2.1463 3.6449) (xy 2.1463 3.6449) (xy 2.1463 -1.6129) (xy 3.81 -1.6129)
				(xy 3.81 4.2926) (xy 2.54 4.2926) (xy 2.54 4.953)
			)
			(stroke
				(width 0)
				(type default)
			)
			(fill no)
			(layer "F.CrtYd")
		)
		(fp_rect
			(start 2.54 4.2926)
			(end 3.81 -4.2926)
			(stroke
				(width 0)
				(type default)
			)
			(fill no)
			(layer "F.Fab")
		)
		(fp_rect
			(start -2.54 4.953)
			(end 2.54 -4.953)
			(stroke
				(width 0)
				(type default)
			)
			(fill no)
			(layer "F.Fab")
		)
		(fp_rect
			(start -3.81 4.2926)
			(end -2.54 -4.2926)
			(stroke
				(width 0)
				(type default)
			)
			(fill no)
			(layer "F.Fab")
		)
		(pad "1" smd rect
			(at 0 -3.1496 180)
			(size 2.413 2.286)
			(layers "F.Cu" "F.Mask" "F.Paste")
			(net "P12V")
		)
		(pad "2" smd rect
			(at 0 3.1496 180)
			(size 2.413 2.286)
			(layers "F.Cu" "F.Mask" "F.Paste")
			(net "GND")
		)
		(zone
			(layer "F.Cu")
			(hatch none 0.5)
			(connect_pads
				(clearance 0)
			)
			(min_thickness 0.25)
			(keepout
				(tracks allowed)
				(vias not_allowed)
				(pads allowed)
				(copperpour not_allowed)
				(footprints allowed)
			)
			(placement
				(enabled no)
				(sheetname "")
			)
			(fill
				(thermal_gap 0.5)
				(thermal_bridge_width 0.5)
				(island_removal_mode 0)
			)
			(polygon
				(pts
					(xy 135.17499 -45.498258) (xy 135.17499 -42.589958) (xy 138.19759 -42.589958) (xy 138.19759 -45.485558)
					(xy 138.19759 -45.815758) (xy 135.17499 -45.815758)
				)
			)
		)
		(zone
			(layer "F.Cu")
			(hatch none 0.5)
			(connect_pads
				(clearance 0)
			)
			(min_thickness 0.25)
			(keepout
				(tracks allowed)
				(vias not_allowed)
				(pads allowed)
				(copperpour not_allowed)
				(footprints allowed)
			)
			(placement
				(enabled no)
				(sheetname "")
			)
			(fill
				(thermal_gap 0.5)
				(thermal_bridge_width 0.5)
				(island_removal_mode 0)
			)
			(polygon
				(pts
					(xy 138.19759 -51.784758) (xy 135.17499 -51.784758) (xy 135.17499 -48.889158) (xy 135.17499 -48.558958)
					(xy 138.19759 -48.558958) (xy 138.19759 -48.889158)
				)
			)
		)
	)
)
